(kicad_pcb
	(version 20241229)
	(generator "pcbnew")
	(generator_version "9.0")
	(general
		(thickness 1.62)
		(legacy_teardrops no)
	)
	(paper "A4")
	(title_block
		(title "OCuLink to 10GbE adapter")
		(date "2026-02-23")
		(rev "1.1.0")
		(company "Antmicro Ltd")
		(comment 1 "www.antmicro.com")
		(comment 9 "footprints 226-230 of 510")
	)
	(layers
		(0 "F.Cu" signal)
		(4 "In1.Cu" signal)
		(6 "In2.Cu" signal)
		(8 "In3.Cu" signal)
		(10 "In4.Cu" signal)
		(12 "In5.Cu" signal)
		(14 "In6.Cu" signal)
		(2 "B.Cu" signal)
		(9 "F.Adhes" user "F.Adhesive")
		(11 "B.Adhes" user "B.Adhesive")
		(13 "F.Paste" user)
		(15 "B.Paste" user)
		(5 "F.SilkS" user "F.Silkscreen")
		(7 "B.SilkS" user "B.Silkscreen")
		(1 "F.Mask" user)
		(3 "B.Mask" user)
		(17 "Dwgs.User" user "User.Drawings")
		(19 "Cmts.User" user "User.Comments")
		(21 "Eco1.User" user "User.Eco1")
		(23 "Eco2.User" user "User.Eco2")
		(25 "Edge.Cuts" user)
		(27 "Margin" user)
		(31 "F.CrtYd" user "F.Courtyard")
		(29 "B.CrtYd" user "B.Courtyard")
		(35 "F.Fab" user)
		(33 "B.Fab" user)
	)
	(footprint "antmicro-footprints:R_0402_1005Metric"
		(layer "F.Cu")
		(at 53.1 85.15 -90)
		(descr "Resistor SMD 0402")
		(tags "resistor SMD 0402")
		(property "Reference" "R10"
			(at -1.04 2.84 90)
			(layer "F.SilkS")
			(effects
				(font
					(size 0.7 0.7)
					(thickness 0.15)
				)
				(justify right top)
			)
		)
		(property "Value" "R_0R_0402"
			(at -1.011843 1.772046 90)
			(layer "F.Fab")
			(hide yes)
			(effects
				(font
					(size 0.7 0.7)
					(thickness 0.15)
				)
				(justify right top)
			)
		)
		(property "Datasheet" "https://industrial.panasonic.com/cdbs/www-data/pdf/RDA0000/AOA0000C301.pdf"
			(at 0 0 90)
			(layer "F.Fab")
			(hide yes)
			(effects
				(font
					(size 1.27 1.27)
					(thickness 0.15)
				)
			)
		)
		(property "Description" "SMD Chip Resistor, Jumper, 0 ohm, 100 mW, 0402 [1005 Metric], Thick Film, General Purpose"
			(at 0 0 90)
			(layer "F.Fab")
			(hide yes)
			(effects
				(font
					(size 1.27 1.27)
					(thickness 0.15)
				)
			)
		)
		(property "MPN" "ERJ2GE0R00X"
			(at 0 0 270)
			(unlocked yes)
			(layer "F.Fab")
			(hide yes)
			(effects
				(font
					(size 1 1)
					(thickness 0.15)
				)
			)
		)
		(property "Manufacturer" "Panasonic"
			(at 0 0 270)
			(unlocked yes)
			(layer "F.Fab")
			(hide yes)
			(effects
				(font
					(size 1 1)
					(thickness 0.15)
				)
			)
		)
		(property "License" "Apache-2.0"
			(at 0 0 270)
			(unlocked yes)
			(layer "F.Fab")
			(hide yes)
			(effects
				(font
					(size 1 1)
					(thickness 0.15)
				)
			)
		)
		(property "Author" "Antmicro"
			(at 0 0 270)
			(unlocked yes)
			(layer "F.Fab")
			(hide yes)
			(effects
				(font
					(size 1 1)
					(thickness 0.15)
				)
			)
		)
		(property "Val" "0R"
			(at 0 0 270)
			(unlocked yes)
			(layer "F.Fab")
			(hide yes)
			(effects
				(font
					(size 1 1)
					(thickness 0.15)
				)
			)
		)
		(property "Tolerance" "~"
			(at 0 0 270)
			(unlocked yes)
			(layer "F.Fab")
			(hide yes)
			(effects
				(font
					(size 1 1)
					(thickness 0.15)
				)
			)
		)
		(property "Current" "1A"
			(at 0 0 270)
			(unlocked yes)
			(layer "F.Fab")
			(hide yes)
			(effects
				(font
					(size 1 1)
					(thickness 0.15)
				)
			)
		)
		(sheetname "/Power/")
		(sheetfile "power.kicad_sch")
		(attr smd)
		(fp_rect
			(start -0.925 -0.47)
			(end 0.925 0.47)
			(stroke
				(width 0.05)
				(type default)
			)
			(fill no)
			(layer "F.CrtYd")
		)
		(fp_rect
			(start -0.5 -0.25)
			(end 0.5 0.25)
			(stroke
				(width 0.15)
				(type solid)
			)
			(fill no)
			(layer "F.Fab")
		)
		(pad "1" smd roundrect
			(at -0.48 0 270)
			(size 0.59 0.64)
			(layers "F.Cu" "F.Mask" "F.Paste")
			(roundrect_rratio 0.25)
			(net 338 "/Power/3V3_PG")
			(pintype "passive")
		)
		(pad "2" smd roundrect
			(at 0.48 0 270)
			(size 0.59 0.64)
			(layers "F.Cu" "F.Mask" "F.Paste")
			(roundrect_rratio 0.25)
			(net 340 "/Power/VCCD_EN")
			(pintype "passive")
		)
	)
	(footprint "antmicro-footprints:C_0603_1608Metric"
		(layer "F.Cu")
		(at 72.9 110.35 90)
		(descr "Capacitor SMD 0603")
		(tags "capacitor 0603")
		(property "Reference" "C165"
			(at -3.62 3.64 90)
			(layer "F.SilkS")
			(effects
				(font
					(size 0.7 0.7)
					(thickness 0.15)
				)
				(justify left bottom)
			)
		)
		(property "Value" "C_10u_10V_X7R_0603"
			(at -1.42757 1.770288 90)
			(layer "F.Fab")
			(hide yes)
			(effects
				(font
					(size 0.7 0.7)
					(thickness 0.15)
				)
				(justify left bottom)
			)
		)
		(property "Datasheet" "https://www.murata.com/products/productdetail?partno=GRM188Z71A106KA73%23"
			(at 0 0 90)
			(layer "F.Fab")
			(hide yes)
			(effects
				(font
					(size 1.27 1.27)
					(thickness 0.15)
				)
			)
		)
		(property "Description" "SMD Multilayer Ceramic Capacitor,  10µF, 10V, 0603, ±10%, X7R"
			(at 0 0 90)
			(layer "F.Fab")
			(hide yes)
			(effects
				(font
					(size 1.27 1.27)
					(thickness 0.15)
				)
			)
		)
		(property "MPN" "GRM188Z71A106KA73D"
			(at 0 0 90)
			(unlocked yes)
			(layer "F.Fab")
			(hide yes)
			(effects
				(font
					(size 1 1)
					(thickness 0.15)
				)
			)
		)
		(property "Val" "10u"
			(at 0 0 90)
			(unlocked yes)
			(layer "F.Fab")
			(hide yes)
			(effects
				(font
					(size 1 1)
					(thickness 0.15)
				)
			)
		)
		(property "Voltage" "10V"
			(at 0 0 90)
			(unlocked yes)
			(layer "F.Fab")
			(hide yes)
			(effects
				(font
					(size 1 1)
					(thickness 0.15)
				)
			)
		)
		(property "Dielectric" "X7R"
			(at 0 0 90)
			(unlocked yes)
			(layer "F.Fab")
			(hide yes)
			(effects
				(font
					(size 1 1)
					(thickness 0.15)
				)
			)
		)
		(property "Manufacturer" "Murata"
			(at 0 0 90)
			(unlocked yes)
			(layer "F.Fab")
			(hide yes)
			(effects
				(font
					(size 1 1)
					(thickness 0.15)
				)
			)
		)
		(property "License" "Apache-2.0"
			(at 0 0 90)
			(unlocked yes)
			(layer "F.Fab")
			(hide yes)
			(effects
				(font
					(size 1 1)
					(thickness 0.15)
				)
			)
		)
		(property "Author" "Antmicro"
			(at 0 0 90)
			(unlocked yes)
			(layer "F.Fab")
			(hide yes)
			(effects
				(font
					(size 1 1)
					(thickness 0.15)
				)
			)
		)
		(sheetname "/X710-AT2 power/")
		(sheetfile "x710-at2-power.kicad_sch")
		(attr smd)
		(fp_line
			(start -0.15 -0.4)
			(end 0.15 -0.4)
			(stroke
				(width 0.15)
				(type solid)
			)
			(layer "F.SilkS")
		)
		(fp_line
			(start -0.15 0.4)
			(end 0.15 0.4)
			(stroke
				(width 0.15)
				(type solid)
			)
			(layer "F.SilkS")
		)
		(fp_rect
			(start -1.25 -0.65)
			(end 1.25 0.65)
			(stroke
				(width 0.05)
				(type solid)
			)
			(fill no)
			(layer "F.CrtYd")
		)
		(fp_rect
			(start -0.8 -0.4)
			(end 0.8 0.4)
			(stroke
				(width 0.15)
				(type solid)
			)
			(fill no)
			(layer "F.Fab")
		)
		(pad "1" smd roundrect
			(at -0.7 0 90)
			(size 0.8 1)
			(layers "F.Cu" "F.Mask" "F.Paste")
			(roundrect_rratio 0.2)
			(net 28 "GND")
			(pintype "passive")
		)
		(pad "2" smd roundrect
			(at 0.7 0 90)
			(size 0.8 1)
			(layers "F.Cu" "F.Mask" "F.Paste")
			(roundrect_rratio 0.2)
			(net 5 "P0_AVDDL")
			(pintype "passive")
		)
	)
	(footprint "antmicro-footprints:C_0603_1608Metric_EIA"
		(layer "F.Cu")
		(at 60.649999 108.55)
		(descr "Capacitor SMD 0603, IPC-7351 Density Level A")
		(tags "Capacitor 0603")
		(property "Reference" "C35"
			(at -3.209999 -1.09 0)
			(layer "F.SilkS")
			(effects
				(font
					(size 0.7 0.7)
					(thickness 0.15)
				)
				(justify left bottom)
			)
		)
		(property "Value" "C_22u_16V_0603"
			(at -1.42757 1.770288 0)
			(layer "F.Fab")
			(hide yes)
			(effects
				(font
					(size 0.7 0.7)
					(thickness 0.15)
				)
				(justify left bottom)
			)
		)
		(property "Datasheet" "https://product.samsungsem.com/mlcc/CL10A226MO7JZN.do"
			(at 0 0 0)
			(layer "F.Fab")
			(hide yes)
			(effects
				(font
					(size 1.27 1.27)
					(thickness 0.15)
				)
			)
		)
		(property "Description" "SMD Multilayer Ceramic Capacitor"
			(at 0 0 0)
			(layer "F.Fab")
			(hide yes)
			(effects
				(font
					(size 1.27 1.27)
					(thickness 0.15)
				)
			)
		)
		(property "MPN" "CL10A226MO7JZNC"
			(at 0 0 0)
			(unlocked yes)
			(layer "F.Fab")
			(hide yes)
			(effects
				(font
					(size 1 1)
					(thickness 0.15)
				)
			)
		)
		(property "Manufacturer" "Samsung Electro-Mechanics"
			(at 0 0 0)
			(unlocked yes)
			(layer "F.Fab")
			(hide yes)
			(effects
				(font
					(size 1 1)
					(thickness 0.15)
				)
			)
		)
		(property "License" "Apache-2.0"
			(at 0 0 0)
			(unlocked yes)
			(layer "F.Fab")
			(hide yes)
			(effects
				(font
					(size 1 1)
					(thickness 0.15)
				)
			)
		)
		(property "Author" "Antmicro"
			(at 0 0 0)
			(unlocked yes)
			(layer "F.Fab")
			(hide yes)
			(effects
				(font
					(size 1 1)
					(thickness 0.15)
				)
			)
		)
		(property "Val" "22u"
			(at 0 0 0)
			(unlocked yes)
			(layer "F.Fab")
			(hide yes)
			(effects
				(font
					(size 1 1)
					(thickness 0.15)
				)
			)
		)
		(property "Voltage" "16V"
			(at 0 0 0)
			(unlocked yes)
			(layer "F.Fab")
			(hide yes)
			(effects
				(font
					(size 1 1)
					(thickness 0.15)
				)
			)
		)
		(property "Dielectric" ""
			(at 0 0 0)
			(unlocked yes)
			(layer "F.Fab")
			(hide yes)
			(effects
				(font
					(size 1 1)
					(thickness 0.15)
				)
			)
		)
		(property "Public" "False"
			(at 0 0 0)
			(unlocked yes)
			(layer "F.Fab")
			(hide yes)
			(effects
				(font
					(size 1 1)
					(thickness 0.15)
				)
			)
		)
		(sheetname "/Power/")
		(sheetfile "power.kicad_sch")
		(attr smd)
		(fp_line
			(start -0.15 -0.55)
			(end 0.15 -0.55)
			(stroke
				(width 0.15)
				(type solid)
			)
			(layer "F.SilkS")
		)
		(fp_line
			(start -0.15 0.55)
			(end 0.15 0.55)
			(stroke
				(width 0.15)
				(type solid)
			)
			(layer "F.SilkS")
		)
		(fp_rect
			(start -1.25 -0.65)
			(end 1.25 0.65)
			(stroke
				(width 0.05)
				(type solid)
			)
			(fill no)
			(layer "F.CrtYd")
		)
		(fp_rect
			(start -0.8 -0.45)
			(end 0.8 0.45)
			(stroke
				(width 0.15)
				(type solid)
			)
			(fill no)
			(layer "F.Fab")
		)
		(pad "1" smd roundrect
			(at -0.7 0)
			(size 0.8 1.1)
			(layers "F.Cu" "F.Mask" "F.Paste")
			(roundrect_rratio 0.2)
			(net 28 "GND")
			(pintype "passive")
		)
		(pad "2" smd roundrect
			(at 0.7 0)
			(size 0.8 1.1)
			(layers "F.Cu" "F.Mask" "F.Paste")
			(roundrect_rratio 0.2)
			(net 312 "/Power/+1V0_OUT")
			(pintype "passive")
		)
	)
	(footprint "antmicro-footprints:C_0402_1005Metric"
		(layer "F.Cu")
		(at 109.35 95.35 -90)
		(descr "Capacitor SMD 0402")
		(tags "capacitor SMD 0402")
		(property "Reference" "C216"
			(at -2.9 -0.334999 90)
			(layer "F.SilkS")
			(effects
				(font
					(size 0.7 0.7)
					(thickness 0.15)
				)
				(justify left bottom)
			)
		)
		(property "Value" "C_10p_0402"
			(at -1.022927 2.155213 90)
			(layer "F.Fab")
			(hide yes)
			(effects
				(font
					(size 0.7 0.7)
					(thickness 0.15)
				)
				(justify right top)
			)
		)
		(property "Datasheet" "https://www.murata.com/products/productdetail?partno=GCM1555C1H100GA16%23"
			(at 0 0 90)
			(layer "F.Fab")
			(hide yes)
			(effects
				(font
					(size 1.27 1.27)
					(thickness 0.15)
				)
			)
		)
		(property "Description" "SMD Multilayer Ceramic Capacitor, 10 pF, 50 V, 0402 [1005 Metric], ± 2%, C0G / NP0, GCM"
			(at 0 0 90)
			(layer "F.Fab")
			(hide yes)
			(effects
				(font
					(size 1.27 1.27)
					(thickness 0.15)
				)
			)
		)
		(property "MPN" "GCM1555C1H100GA16D"
			(at 0 0 270)
			(unlocked yes)
			(layer "F.Fab")
			(hide yes)
			(effects
				(font
					(size 1 1)
					(thickness 0.15)
				)
			)
		)
		(property "Manufacturer" "Murata"
			(at 0 0 270)
			(unlocked yes)
			(layer "F.Fab")
			(hide yes)
			(effects
				(font
					(size 1 1)
					(thickness 0.15)
				)
			)
		)
		(property "License" "Apache-2.0"
			(at 0 0 270)
			(unlocked yes)
			(layer "F.Fab")
			(hide yes)
			(effects
				(font
					(size 1 1)
					(thickness 0.15)
				)
			)
		)
		(property "Author" "Antmicro"
			(at 0 0 270)
			(unlocked yes)
			(layer "F.Fab")
			(hide yes)
			(effects
				(font
					(size 1 1)
					(thickness 0.15)
				)
			)
		)
		(property "Val" "10p"
			(at 0 0 270)
			(unlocked yes)
			(layer "F.Fab")
			(hide yes)
			(effects
				(font
					(size 1 1)
					(thickness 0.15)
				)
			)
		)
		(property "Voltage" "50V"
			(at 0 0 270)
			(unlocked yes)
			(layer "F.Fab")
			(hide yes)
			(effects
				(font
					(size 1 1)
					(thickness 0.15)
				)
			)
		)
		(property "Dielectric" "C0G"
			(at 0 0 270)
			(unlocked yes)
			(layer "F.Fab")
			(hide yes)
			(effects
				(font
					(size 1 1)
					(thickness 0.15)
				)
			)
		)
		(sheetname "/X710-AT2 10GbE/")
		(sheetfile "x710-at2-10gbe.kicad_sch")
		(attr smd)
		(fp_rect
			(start -0.925 -0.47)
			(end 0.925 0.47)
			(stroke
				(width 0.05)
				(type default)
			)
			(fill no)
			(layer "F.CrtYd")
		)
		(fp_line
			(start -0.494 0.248)
			(end -0.494 -0.25)
			(stroke
				(width 0.15)
				(type solid)
			)
			(layer "F.Fab")
		)
		(fp_line
			(start 0.504 0.248)
			(end -0.494 0.248)
			(stroke
				(width 0.15)
				(type solid)
			)
			(layer "F.Fab")
		)
		(fp_line
			(start -0.494 -0.25)
			(end 0.504 -0.25)
			(stroke
				(width 0.15)
				(type solid)
			)
			(layer "F.Fab")
		)
		(fp_line
			(start 0.504 -0.25)
			(end 0.504 0.248)
			(stroke
				(width 0.15)
				(type solid)
			)
			(layer "F.Fab")
		)
		(fp_text user "License: Apache-2.0"
			(at -0.939 5.799 270)
			(layer "F.Fab")
			(effects
				(font
					(size 0.7 0.7)
					(thickness 0.15)
				)
				(justify left bottom)
			)
		)
		(fp_text user "Author: Antmicro"
			(at -0.939 3.399 270)
			(layer "F.Fab")
			(effects
				(font
					(size 0.7 0.7)
					(thickness 0.15)
				)
				(justify left bottom)
			)
		)
		(fp_text user "${REFERENCE}"
			(at -0.939 4.599 270)
			(layer "F.Fab")
			(effects
				(font
					(size 0.7 0.7)
					(thickness 0.15)
				)
				(justify left bottom)
			)
		)
		(pad "1" smd roundrect
			(at -0.48 0 270)
			(size 0.59 0.64)
			(layers "F.Cu" "F.Mask" "F.Paste")
			(roundrect_rratio 0.25)
			(net 28 "GND")
			(pintype "passive")
		)
		(pad "2" smd roundrect
			(at 0.48 0 270)
			(size 0.59 0.64)
			(layers "F.Cu" "F.Mask" "F.Paste")
			(roundrect_rratio 0.25)
			(net 288 "/X710-AT2 10GbE/MDIO0_I2C0.MDC")
			(pintype "passive")
		)
	)
	(footprint "antmicro-footprints:R_0402_1005Metric"
		(layer "F.Cu")
		(at 53.099998 92.85 -90)
		(descr "Resistor SMD 0402")
		(tags "resistor SMD 0402")
		(property "Reference" "R30"
			(at -1.05 2.889998 90)
			(layer "F.SilkS")
			(effects
				(font
					(size 0.7 0.7)
					(thickness 0.15)
				)
				(justify right top)
			)
		)
		(property "Value" "R_0R_0402"
			(at -1.011843 1.772046 90)
			(layer "F.Fab")
			(hide yes)
			(effects
				(font
					(size 0.7 0.7)
					(thickness 0.15)
				)
				(justify right top)
			)
		)
		(property "Datasheet" "https://industrial.panasonic.com/cdbs/www-data/pdf/RDA0000/AOA0000C301.pdf"
			(at 0 0 90)
			(layer "F.Fab")
			(hide yes)
			(effects
				(font
					(size 1.27 1.27)
					(thickness 0.15)
				)
			)
		)
		(property "Description" "SMD Chip Resistor, Jumper, 0 ohm, 100 mW, 0402 [1005 Metric], Thick Film, General Purpose"
			(at 0 0 90)
			(layer "F.Fab")
			(hide yes)
			(effects
				(font
					(size 1.27 1.27)
					(thickness 0.15)
				)
			)
		)
		(property "MPN" "ERJ2GE0R00X"
			(at 0 0 270)
			(unlocked yes)
			(layer "F.Fab")
			(hide yes)
			(effects
				(font
					(size 1 1)
					(thickness 0.15)
				)
			)
		)
		(property "Manufacturer" "Panasonic"
			(at 0 0 270)
			(unlocked yes)
			(layer "F.Fab")
			(hide yes)
			(effects
				(font
					(size 1 1)
					(thickness 0.15)
				)
			)
		)
		(property "License" "Apache-2.0"
			(at 0 0 270)
			(unlocked yes)
			(layer "F.Fab")
			(hide yes)
			(effects
				(font
					(size 1 1)
					(thickness 0.15)
				)
			)
		)
		(property "Author" "Antmicro"
			(at 0 0 270)
			(unlocked yes)
			(layer "F.Fab")
			(hide yes)
			(effects
				(font
					(size 1 1)
					(thickness 0.15)
				)
			)
		)
		(property "Val" "0R"
			(at 0 0 270)
			(unlocked yes)
			(layer "F.Fab")
			(hide yes)
			(effects
				(font
					(size 1 1)
					(thickness 0.15)
				)
			)
		)
		(property "Tolerance" "~"
			(at 0 0 270)
			(unlocked yes)
			(layer "F.Fab")
			(hide yes)
			(effects
				(font
					(size 1 1)
					(thickness 0.15)
				)
			)
		)
		(property "Current" "1A"
			(at 0 0 270)
			(unlocked yes)
			(layer "F.Fab")
			(hide yes)
			(effects
				(font
					(size 1 1)
					(thickness 0.15)
				)
			)
		)
		(sheetname "/Power/")
		(sheetfile "power.kicad_sch")
		(attr smd)
		(fp_rect
			(start -0.925 -0.47)
			(end 0.925 0.47)
			(stroke
				(width 0.05)
				(type default)
			)
			(fill no)
			(layer "F.CrtYd")
		)
		(fp_rect
			(start -0.5 -0.25)
			(end 0.5 0.25)
			(stroke
				(width 0.15)
				(type solid)
			)
			(fill no)
			(layer "F.Fab")
		)
		(pad "1" smd roundrect
			(at -0.48 0 270)
			(size 0.59 0.64)
			(layers "F.Cu" "F.Mask" "F.Paste")
			(roundrect_rratio 0.25)
			(net 341 "/Power/1V0_PG")
			(pintype "passive")
		)
		(pad "2" smd roundrect
			(at 0.48 0 270)
			(size 0.59 0.64)
			(layers "F.Cu" "F.Mask" "F.Paste")
			(roundrect_rratio 0.25)
			(net 376 "/Power/DVDD_EN")
			(pintype "passive")
		)
	)
)
